# T6G (Grand Teton) — schematic netlist excerpt (pin names and nets, part order shuffled) for the footprints in the layout excerpt that follows; sources: Cadence DE-HDL packaged netlist, KiCad conversion of 04192023_DAF0TMB3IC0_F0TG_MB_C_brd_V02_OCP.brd

R4072  Q_RES  10K 1% CHIP  pkg 0402LF  page 146 : A = P12V_AUX ; B = P3V3_E1S_0_EN_G
R1315  Q_RES  0 5% CHIP  pkg 0402LF  page 252 : A = SMB_ADC_SCL ; B = SMB_ADC_SCL_R

(kicad_pcb
	(version 20260206)
	(generator "pcbnew")
	(generator_version "10.0")
	(general
		(thickness 1.6)
		(legacy_teardrops no)
	)
	(paper "A4")
	(title_block
		(title "04192023_DAF0TMB3IC0_F0TG_MB_C_brd_V02_OCP.brd")
		(comment 1 "Grand Teton / footprints 3086-3087 of 8354")
	)
	(layers
		(0 "F.Cu" signal "TOP")
		(4 "In1.Cu" signal "GND")
		(6 "In2.Cu" signal "IN1")
		(8 "In3.Cu" signal "GND1")
		(10 "In4.Cu" signal "IN2")
		(12 "In5.Cu" signal "GND2")
		(14 "In6.Cu" signal "IN3")
		(16 "In7.Cu" signal "GND3")
		(18 "In8.Cu" signal "VCC")
		(20 "In9.Cu" signal "VCC1")
		(22 "In10.Cu" signal "GND4")
		(24 "In11.Cu" signal "IN4")
		(26 "In12.Cu" signal "GND5")
		(28 "In13.Cu" signal "IN5")
		(30 "In14.Cu" signal "GND6")
		(32 "In15.Cu" signal "IN6")
		(34 "In16.Cu" signal "GND7")
		(2 "B.Cu" signal "BOTTOM")
		(9 "F.Adhes" user "F.Adhesive")
		(11 "B.Adhes" user "B.Adhesive")
		(13 "F.Paste" user "Package Geometry/Pastemask Top")
		(15 "B.Paste" user "Package Geometry/Pastemask Bottom")
		(5 "F.SilkS" user "Ref Des/Silkscreen Top")
		(7 "B.SilkS" user "Ref Des/Silkscreen Bottom")
		(1 "F.Mask" user "Board Geometry/Soldermask Top")
		(3 "B.Mask" user "Board Geometry/Soldermask Bottom")
		(17 "Dwgs.User" user "User.Drawings")
		(19 "Cmts.User" user "User.Comments")
		(21 "Eco1.User" user "User.Eco1")
		(23 "Eco2.User" user "User.Eco2")
		(25 "Edge.Cuts" user "Board Geometry/Outline")
		(27 "Margin" user)
		(31 "F.CrtYd" user "Package Geometry/Place Bound Top")
		(29 "B.CrtYd" user "Package Geometry/Place Bound Bottom")
		(35 "F.Fab" user "Ref Des/Assembly Top")
		(33 "B.Fab" user "Ref Des/Assembly Bottom")
	)
	(footprint ""
		(layer "F.Cu")
		(at 271.092676 -119.761)
		(property "Reference" "R1315"
			(at 0 0 0)
			(layer "F.SilkS")
			(hide yes)
			(effects
				(font
					(size 1.27 1.27)
				)
			)
		)
		(property "Value" ""
			(at 0 0 0)
			(layer "F.Fab")
			(effects
				(font
					(size 1.27 1.27)
				)
			)
		)
		(duplicate_pad_numbers_are_jumpers no)
		(fp_line
			(start -0.7874 -0.4064)
			(end 0.7874 -0.4064)
			(stroke
				(width 0.1524)
				(type default)
			)
			(layer "F.SilkS")
		)
		(fp_line
			(start -0.7874 0.4064)
			(end -0.7874 -0.4064)
			(stroke
				(width 0.1524)
				(type default)
			)
			(layer "F.SilkS")
		)
		(fp_line
			(start 0.7874 -0.4064)
			(end 0.7874 0.4064)
			(stroke
				(width 0.1524)
				(type default)
			)
			(layer "F.SilkS")
		)
		(fp_line
			(start 0.7874 0.4064)
			(end -0.7874 0.4064)
			(stroke
				(width 0.1524)
				(type default)
			)
			(layer "F.SilkS")
		)
		(fp_line
			(start -0.67945 -0.305054)
			(end -0.12065 -0.305054)
			(stroke
				(width 0.1)
				(type default)
			)
			(layer "F.Fab")
		)
		(fp_line
			(start -0.67945 0.3048)
			(end -0.67945 -0.305054)
			(stroke
				(width 0.1)
				(type default)
			)
			(layer "F.Fab")
		)
		(fp_line
			(start -0.12065 -0.305054)
			(end -0.12065 -0.2794)
			(stroke
				(width 0.1)
				(type default)
			)
			(layer "F.Fab")
		)
		(fp_line
			(start -0.12065 -0.2794)
			(end 0.12065 -0.2794)
			(stroke
				(width 0.1)
				(type default)
			)
			(layer "F.Fab")
		)
		(fp_line
			(start -0.12065 0.2794)
			(end -0.12065 0.3048)
			(stroke
				(width 0.1)
				(type default)
			)
			(layer "F.Fab")
		)
		(fp_line
			(start -0.12065 0.3048)
			(end -0.67945 0.3048)
			(stroke
				(width 0.1)
				(type default)
			)
			(layer "F.Fab")
		)
		(fp_line
			(start 0.120396 0.2794)
			(end -0.12065 0.2794)
			(stroke
				(width 0.1)
				(type default)
			)
			(layer "F.Fab")
		)
		(fp_line
			(start 0.120396 0.3048)
			(end 0.120396 0.2794)
			(stroke
				(width 0.1)
				(type default)
			)
			(layer "F.Fab")
		)
		(fp_line
			(start 0.12065 -0.3048)
			(end 0.67945 -0.3048)
			(stroke
				(width 0.1)
				(type default)
			)
			(layer "F.Fab")
		)
		(fp_line
			(start 0.12065 -0.2794)
			(end 0.12065 -0.3048)
			(stroke
				(width 0.1)
				(type default)
			)
			(layer "F.Fab")
		)
		(fp_line
			(start 0.67945 -0.3048)
			(end 0.67945 0.3048)
			(stroke
				(width 0.1)
				(type default)
			)
			(layer "F.Fab")
		)
		(fp_line
			(start 0.67945 0.3048)
			(end 0.120396 0.3048)
			(stroke
				(width 0.1)
				(type default)
			)
			(layer "F.Fab")
		)
		(pad "1" smd circle
			(at -0.40005 0)
			(size 0 0)
			(layers "F.Cu" "F.Mask" "F.Paste")
			(net "SMB_ADC_SCL")
		)
		(pad "2" smd circle
			(at 0.40005 0)
			(size 0 0)
			(layers "F.Cu" "F.Mask" "F.Paste")
			(net "SMB_ADC_SCL_R")
		)
	)
	(footprint ""
		(layer "F.Cu")
		(at 257.766312 -69.196458 90)
		(property "Reference" "R4072"
			(at 0 0 90)
			(layer "F.SilkS")
			(hide yes)
			(effects
				(font
					(size 1.27 1.27)
				)
			)
		)
		(property "Value" ""
			(at 0 0 90)
			(layer "F.Fab")
			(effects
				(font
					(size 1.27 1.27)
				)
			)
		)
		(duplicate_pad_numbers_are_jumpers no)
		(fp_line
			(start 0.7874 -0.4064)
			(end 0.7874 0.4064)
			(stroke
				(width 0.1524)
				(type default)
			)
			(layer "F.SilkS")
		)
		(fp_line
			(start -0.7874 -0.4064)
			(end 0.7874 -0.4064)
			(stroke
				(width 0.1524)
				(type default)
			)
			(layer "F.SilkS")
		)
		(fp_line
			(start 0.7874 0.4064)
			(end -0.7874 0.4064)
			(stroke
				(width 0.1524)
				(type default)
			)
			(layer "F.SilkS")
		)
		(fp_line
			(start -0.7874 0.4064)
			(end -0.7874 -0.4064)
			(stroke
				(width 0.1524)
				(type default)
			)
			(layer "F.SilkS")
		)
		(fp_line
			(start -0.12065 -0.305054)
			(end -0.12065 -0.2794)
			(stroke
				(width 0.1)
				(type default)
			)
			(layer "F.Fab")
		)
		(fp_line
			(start -0.67945 -0.305054)
			(end -0.12065 -0.305054)
			(stroke
				(width 0.1)
				(type default)
			)
			(layer "F.Fab")
		)
		(fp_line
			(start 0.67945 -0.3048)
			(end 0.67945 0.3048)
			(stroke
				(width 0.1)
				(type default)
			)
			(layer "F.Fab")
		)
		(fp_line
			(start 0.12065 -0.3048)
			(end 0.67945 -0.3048)
			(stroke
				(width 0.1)
				(type default)
			)
			(layer "F.Fab")
		)
		(fp_line
			(start 0.12065 -0.2794)
			(end 0.12065 -0.3048)
			(stroke
				(width 0.1)
				(type default)
			)
			(layer "F.Fab")
		)
		(fp_line
			(start -0.12065 -0.2794)
			(end 0.12065 -0.2794)
			(stroke
				(width 0.1)
				(type default)
			)
			(layer "F.Fab")
		)
		(fp_line
			(start 0.120396 0.2794)
			(end -0.12065 0.2794)
			(stroke
				(width 0.1)
				(type default)
			)
			(layer "F.Fab")
		)
		(fp_line
			(start -0.12065 0.2794)
			(end -0.12065 0.3048)
			(stroke
				(width 0.1)
				(type default)
			)
			(layer "F.Fab")
		)
		(fp_line
			(start 0.67945 0.3048)
			(end 0.120396 0.3048)
			(stroke
				(width 0.1)
				(type default)
			)
			(layer "F.Fab")
		)
		(fp_line
			(start 0.120396 0.3048)
			(end 0.120396 0.2794)
			(stroke
				(width 0.1)
				(type default)
			)
			(layer "F.Fab")
		)
		(fp_line
			(start -0.12065 0.3048)
			(end -0.67945 0.3048)
			(stroke
				(width 0.1)
				(type default)
			)
			(layer "F.Fab")
		)
		(fp_line
			(start -0.67945 0.3048)
			(end -0.67945 -0.305054)
			(stroke
				(width 0.1)
				(type default)
			)
			(layer "F.Fab")
		)
		(pad "1" smd circle
			(at -0.40005 0 90)
			(size 0 0)
			(layers "F.Cu" "F.Mask" "F.Paste")
			(net "P12V_AUX")
		)
		(pad "2" smd circle
			(at 0.40005 0 90)
			(size 0 0)
			(layers "F.Cu" "F.Mask" "F.Paste")
			(net "P3V3_E1S_0_EN_G")
		)
	)
)
